#ISCELL
  mstr_misc dns *
  *
#ISCELL
  pure_quanta quanta_title_block_c *
  *
#CELL
  pure_quanta tusb8042airgcr *
  page157_i119
#CELL
  pure_quanta q_res *
  page157_i122
#CELL
  pure_quanta q_res *
  page157_i124
#CELL
  pure_quanta q_res *
  page157_i125
#ISCELL
  pure_quanta_power universal_power *
  page157_i128
#ISCELL
  pure_quanta_power gnd *
  page157_i129
#CELL
  pure_quanta q_res *
  page157_i130
#CELL
  pure_quanta q_res *
  page157_i131
#ISCELL
  pure_quanta_power universal_power *
  page157_i132
#ISCELL
  pure_quanta_power universal_power *
  page157_i133
#CELL
  pure_quanta q_res *
  page157_i134
#CELL
  pure_quanta q_res *
  page157_i136
#ISCELL
  pure_quanta_power universal_power *
  page157_i137
#CELL
  pure_quanta q_res *
  page157_i138
#CELL
  pure_quanta q_res *
  page157_i139
#ISCELL
  pure_quanta_power gnd *
  page157_i140
#CELL
  pure_quanta q_res *
  page157_i142
#CELL
  pure_quanta q_res *
  page157_i145
#CELL
  pure_quanta q_res *
  page157_i146
#ISCELL
  standard offpage *
  page157_i147
#CELL
  pure_quanta q_res *
  page157_i148
#ISCELL
  standard offpage *
  page157_i149
#CELL
  pure_quanta q_res *
  page157_i150
#CELL
  pure_quanta q_res *
  page157_i151
#ISCELL
  pure_quanta_power universal_power *
  page157_i152
#CELL
  pure_quanta q_res *
  page157_i153
#ISCELL
  pure_quanta_power universal_power *
  page157_i154
#CELL
  pure_quanta q_res *
  page157_i155
#CELL
  pure_quanta q_res *
  page157_i156
#ISCELL
  pure_quanta_power gnd *
  page157_i157
#CELL
  pure_quanta q_res *
  page157_i158
#ISCELL
  pure_quanta_power gnd *
  page157_i159
#CELL
  pure_quanta q_res *
  page157_i160
#ISCELL
  pure_quanta_power gnd *
  page157_i162
#ISCELL
  pure_quanta_power gnd *
  page157_i163
#CELL
  pure_quanta q_xtal_4p_13bi_24gnd *
  page157_i164
#ISCELL
  pure_quanta_power gnd *
  page157_i166
#ISCELL
  pure_quanta_power gnd *
  page157_i167
#ISCELL
  standard offpage *
  page157_i168
#ISCELL
  pure_quanta_power universal_power *
  page157_i169
#CELL
  pure_quanta q_inductor *
  page157_i17
#CELL
  pure_quanta q_res *
  page157_i170
#CELL
  pure_quanta q_res *
  page157_i171
#CELL
  pure_quanta q_cap *
  page157_i174
#CELL
  pure_quanta q_cap *
  page157_i175
#ISCELL
  pure_quanta_power universal_power *
  page157_i18
#ISCELL
  pure_quanta_power universal_power *
  page157_i19
#CELL
  pure_quanta q_inductor *
  page157_i20
#CELL
  pure_quanta q_cap *
  page157_i21
#CELL
  pure_quanta q_cap *
  page157_i22
#CELL
  pure_quanta q_cap *
  page157_i23
#CELL
  pure_quanta q_cap *
  page157_i24
#CELL
  pure_quanta q_cap *
  page157_i25
#CELL
  pure_quanta q_cap *
  page157_i26
#CELL
  pure_quanta q_cap *
  page157_i27
#CELL
  pure_quanta q_cap *
  page157_i28
#CELL
  pure_quanta q_cap *
  page157_i29
#CELL
  pure_quanta q_cap *
  page157_i30
#CELL
  pure_quanta q_cap *
  page157_i31
#CELL
  pure_quanta q_cap *
  page157_i32
#CELL
  pure_quanta q_cap *
  page157_i33
#ISCELL
  pure_quanta_power gnd *
  page157_i34
#ISCELL
  pure_quanta_power universal_power *
  page157_i35
#CELL
  pure_quanta q_cap *
  page157_i36
#ISCELL
  pure_quanta_power universal_power *
  page157_i37
#ISCELL
  pure_quanta_power gnd *
  page157_i38
#CELL
  pure_quanta q_cap *
  page157_i39
#CELL
  pure_quanta q_cap *
  page157_i40
#CELL
  pure_quanta q_cap *
  page157_i41
#CELL
  pure_quanta q_cap *
  page157_i42
#CELL
  pure_quanta q_cap *
  page157_i43
#CELL
  pure_quanta q_cap *
  page157_i44
#CELL
  pure_quanta q_cap *
  page157_i45
#CELL
  pure_quanta q_cap *
  page157_i46
#CELL
  pure_quanta q_cap *
  page157_i47
#CELL
  pure_quanta q_cap *
  page157_i48
#CELL
  pure_quanta q_cap *
  page157_i49
#CELL
  pure_quanta q_cap *
  page157_i50
#CELL
  pure_quanta q_cap *
  page157_i51
#CELL
  pure_quanta q_cap *
  page157_i52
#CELL
  pure_quanta q_cap *
  page157_i53
#CELL
  pure_quanta q_cap *
  page157_i54
#ISCELL
  pure_quanta_power gnd *
  page157_i61
#CELL
  pure_quanta q_res *
  page157_i63
#ISCELL
  pure_quanta_power universal_power *
  page157_i64
#ISCELL
  standard offpage *
  page157_i74
#CELL
  pure_quanta q_res *
  page157_i75
#CELL
  pure_quanta q_res *
  page157_i76
#CELL
  pure_quanta q_res *
  page157_i77
#ISCELL
  pure_quanta_power universal_power *
  page157_i78
#CELL
  pure_quanta q_res *
  page157_i79
#ISCELL
  pure_quanta_power gnd *
  page157_i80
#CELL
  pure_quanta q_res *
  page157_i81
#ISCELL
  pure_quanta_power universal_power *
  page157_i82
